# BASEBOARD_FAB2 (Tioga Pass) — schematic netlist excerpt (pin names and nets, part order shuffled) for the footprints in the layout excerpt that follows; sources: Cadence DE-HDL packaged netlist, KiCad conversion of Wiwynn_Tioga_Pass_MB.brd

J9L2  SCONN288_H44441003  SCONN  pkg PIP  page 86
  \12v\(1)  = P12V_NVDIMM_KLM
  VSS(93)  = GND
  DQ(4)  = M_L_DQ<4>
  VSS(92)  = GND
  DQ(0)  = M_L_DQ<0>
  VSS(91)  = GND
  DQS9P  = M_L_DQS_DP<9>
  DQS9N  = M_L_DQS_DN<9>
  VSS(90)  = GND
  DQ(6)  = M_L_DQ<6>
  VSS(89)  = GND
  DQ(2)  = M_L_DQ<2>
  VSS(88)  = GND
  DQ(12)  = M_L_DQ<12>
  VSS(87)  = GND
  DQ(8)  = M_L_DQ<8>
  VSS(86)  = GND
  DQS10P  = M_L_DQS_DP<10>
  DQS10N  = M_L_DQS_DN<10>
  VSS(85)  = GND
  DQ(14)  = M_L_DQ<14>
  VSS(84)  = GND
  DQ(10)  = M_L_DQ<10>
  VSS(83)  = GND
  DQ(20)  = M_L_DQ<20>
  VSS(82)  = GND
  DQ(16)  = M_L_DQ<16>
  VSS(81)  = GND
  DQS11P  = M_L_DQS_DP<11>
  DQS11N  = M_L_DQS_DN<11>
  VSS(80)  = GND
  DQ(22)  = M_L_DQ<22>
  VSS(79)  = GND
  DQ(18)  = M_L_DQ<18>
  VSS(78)  = GND
  DQ(28)  = M_L_DQ<28>
  VSS(77)  = GND
  DQ(24)  = M_L_DQ<24>
  VSS(76)  = GND
  DQS12P  = M_L_DQS_DP<12>
  DQS12N  = M_L_DQS_DN<12>
  VSS(75)  = GND
  DQ(30)  = M_L_DQ<30>
  VSS(74)  = GND
  DQ(26)  = M_L_DQ<26>
  VSS(73)  = GND
  CB(4)  = M_L_ECC<4>
  VSS(72)  = GND
  CB(0)  = M_L_ECC<0>
  VSS(71)  = GND
  DQS17P  = M_L_DQS_DP<17>
  DQS17N  = M_L_DQS_DN<17>
  VSS(70)  = GND
  CB(6)  = M_L_ECC<6>
  VSS(69)  = GND
  CB(2)  = M_L_ECC<2>
  VSS(68)  = GND
  RESET_N  = M_KLM_RST_N
  VDD(25)  = PVDDQ_KLM
  CKE(0)  = M_L_CKE<2>
  VDD(24)  = PVDDQ_KLM
  ACT_N  = M_L_ACT_N
  BG(0)  = M_L_BG<0>
  VDD(23)  = PVDDQ_KLM
  A12  = M_L_MA<12>
  A9  = M_L_MA<9>
  VDD(22)  = PVDDQ_KLM
  A8  = M_L_MA<8>
  A6  = M_L_MA<6>
  VDD(21)  = PVDDQ_KLM
  A3  = M_L_MA<3>
  A1  = M_L_MA<1>
  VDD(20)  = PVDDQ_KLM
  CK0P  = M_L_CLK_DP<2>
  CK0N  = M_L_CLK_DN<2>
  VDD(19)  = PVDDQ_KLM
  VTT(1)  = PVTT_KLM
  EVENT_N  = FM_DIMM_EVENT_COD_N
  A0  = M_L_MA<0>
  VDD(18)  = PVDDQ_KLM
  BA(0)  = M_L_BA<0>
  A16_RAS_N  = M_L_MA<16>
  VDD(17)  = PVDDQ_KLM
  S0_N  = M_L_CS_N<4>
  VDD(16)  = PVDDQ_KLM
  A15_CAS_N  = M_L_MA<15>
  ODT(0)  = M_L_ODT<2>
  VDD(15)  = PVDDQ_KLM
  S1_N  = M_L_CS_N<5>
  VDD(14)  = PVDDQ_KLM
  ODT(1)  = M_L_ODT<3>
  VDD(13)  = PVDDQ_KLM
  S2_N_C(0)  = M_L_CS_N<6>
  VSS(67)  = GND
  DQ(36)  = M_L_DQ<36>
  VSS(66)  = GND
  DQ(32)  = M_L_DQ<32>
  VSS(65)  = GND
  DQS13P  = M_L_DQS_DP<13>
  DQS13N  = M_L_DQS_DN<13>
  VSS(64)  = GND
  DQ(38)  = M_L_DQ<38>
  VSS(63)  = GND
  DQ(34)  = M_L_DQ<34>
  VSS(62)  = GND
  DQ(44)  = M_L_DQ<44>
  VSS(61)  = GND
  DQ(40)  = M_L_DQ<40>
  VSS(60)  = GND
  DQS14P  = M_L_DQS_DP<14>
  DQS14N  = M_L_DQS_DN<14>
  VSS(59)  = GND
  DQ(46)  = M_L_DQ<46>
  VSS(58)  = GND
  DQ(42)  = M_L_DQ<42>
  VSS(57)  = GND
  DQ(52)  = M_L_DQ<52>
  VSS(56)  = GND
  DQ(48)  = M_L_DQ<48>
  VSS(55)  = GND
  DQS15P  = M_L_DQS_DP<15>
  DQS15N  = M_L_DQS_DN<15>
  VSS(54)  = GND
  DQ(54)  = M_L_DQ<54>
  VSS(53)  = GND
  DQ(50)  = M_L_DQ<50>
  VSS(52)  = GND
  DQ(60)  = M_L_DQ<60>
  VSS(51)  = GND
  DQ(56)  = M_L_DQ<56>
  VSS(50)  = GND
  DQS16P  = M_L_DQS_DP<16>
  DQS16N  = M_L_DQS_DN<16>
  VSS(49)  = GND
  DQ(62)  = M_L_DQ<62>
  VSS(48)  = GND
  DQ(58)  = M_L_DQ<58>
  VSS(47)  = GND
  SA(0)  = PVPP_KLM
  SA(1)  = PVPP_KLM
  SCL  = SMB_DDR_KLM_VPP_SCL
  VPP(4)  = PVPP_KLM
  VPP(3)  = PVPP_KLM
  RFU(2)  = TP_CH_L_DIMM0_RFU_2
  \12v\(0)  = P12V_NVDIMM_KLM
  VREFCA  = M_L_VREF
  VSS(46)  = GND
  DQ(5)  = M_L_DQ<5>
  VSS(45)  = GND
  DQ(1)  = M_L_DQ<1>
  VSS(44)  = GND
  DQS0N  = M_L_DQS_DN<0>
  DQS0P  = M_L_DQS_DP<0>
  VSS(43)  = GND
  DQ(7)  = M_L_DQ<7>
  VSS(42)  = GND
  DQ(3)  = M_L_DQ<3>
  VSS(41)  = GND
  DQ(13)  = M_L_DQ<13>
  VSS(40)  = GND
  DQ(9)  = M_L_DQ<9>
  VSS(39)  = GND
  DQS1N  = M_L_DQS_DN<1>
  DQS1P  = M_L_DQS_DP<1>
  VSS(38)  = GND
  DQ(15)  = M_L_DQ<15>
  VSS(37)  = GND
  DQ(11)  = M_L_DQ<11>
  VSS(36)  = GND
  DQ(21)  = M_L_DQ<21>
  VSS(35)  = GND
  DQ(17)  = M_L_DQ<17>
  VSS(34)  = GND
  DQS2N  = M_L_DQS_DN<2>
  DQS2P  = M_L_DQS_DP<2>
  VSS(33)  = GND
  DQ(23)  = M_L_DQ<23>
  VSS(32)  = GND
  DQ(19)  = M_L_DQ<19>
  VSS(31)  = GND
  DQ(29)  = M_L_DQ<29>
  VSS(30)  = GND
  DQ(25)  = M_L_DQ<25>
  VSS(29)  = GND
  DQS3N  = M_L_DQS_DN<3>
  DQS3P  = M_L_DQS_DP<3>
  VSS(28)  = GND
  DQ(31)  = M_L_DQ<31>
  VSS(27)  = GND
  DQ(27)  = M_L_DQ<27>
  VSS(26)  = GND
  CB(5)  = M_L_ECC<5>
  VSS(25)  = GND
  CB(1)  = M_L_ECC<1>
  VSS(24)  = GND
  DQS8N  = M_L_DQS_DN<8>
  DQS8P  = M_L_DQS_DP<8>
  VSS(23)  = GND
  CB(7)  = M_L_ECC<7>
  VSS(22)  = GND
  CB(3)  = M_L_ECC<3>
  VSS(21)  = GND
  CKE(1)  = M_L_CKE<3>
  VDD(12)  = PVDDQ_KLM
  RFU(0)  = TP_CH_L_DIMM0_RFU_0
  VDD(11)  = PVDDQ_KLM
  BG(1)  = M_L_BG<1>
  ALERT_N  = M_L_ALERT_N
  VDD(10)  = PVDDQ_KLM
  A11  = M_L_MA<11>
  A7  = M_L_MA<7>
  VDD(9)  = PVDDQ_KLM
  A5  = M_L_MA<5>
  A4  = M_L_MA<4>
  VDD(8)  = PVDDQ_KLM
  A2  = M_L_MA<2>
  VDD(7)  = PVDDQ_KLM
  CK1P  = M_L_CLK_DP<3>
  CK1N  = M_L_CLK_DN<3>
  VDD(6)  = PVDDQ_KLM
  VTT(0)  = PVTT_KLM
  PAR  = M_L_PAR
  VDD(5)  = PVDDQ_KLM
  BA(1)  = M_L_BA<1>
  A10  = M_L_MA<10>
  VDD(4)  = PVDDQ_KLM
  RFU(1)  = TP_CH_L_DIMM0_RFU_1
  A14_WE_N  = M_L_MA<14>
  VDD(3)  = PVDDQ_KLM
  SAVE_N_NC  = FM_ADR_COMPLETE_KLM_N
  VDD(2)  = PVDDQ_KLM
  A13  = M_L_MA<13>
  VDD(1)  = PVDDQ_KLM
  A17  = M_L_MA<17>
  C(2)  = M_L_C<2>
  VDD(0)  = PVDDQ_KLM
  S3_N_C(1)  = M_L_CS_N<7>
  SA(2)  = GND
  VSS(20)  = GND
  DQ(37)  = M_L_DQ<37>
  VSS(19)  = GND
  DQ(33)  = M_L_DQ<33>
  VSS(18)  = GND
  DQS4N  = M_L_DQS_DN<4>
  DQS4P  = M_L_DQS_DP<4>
  VSS(17)  = GND
  DQ(39)  = M_L_DQ<39>
  VSS(16)  = GND
  DQ(35)  = M_L_DQ<35>
  VSS(15)  = GND
  DQ(45)  = M_L_DQ<45>
  VSS(14)  = GND
  DQ(41)  = M_L_DQ<41>
  VSS(13)  = GND
  DQS5N  = M_L_DQS_DN<5>
  DQS5P  = M_L_DQS_DP<5>
  VSS(12)  = GND
  DQ(47)  = M_L_DQ<47>
  VSS(11)  = GND
  DQ(43)  = M_L_DQ<43>
  VSS(10)  = GND
  DQ(53)  = M_L_DQ<53>
  VSS(9)  = GND
  DQ(49)  = M_L_DQ<49>
  VSS(8)  = GND
  DQS6N  = M_L_DQS_DN<6>
  DQS6P  = M_L_DQS_DP<6>
  VSS(7)  = GND
  DQ(55)  = M_L_DQ<55>
  VSS(6)  = GND
  DQ(51)  = M_L_DQ<51>
  VSS(5)  = GND
  DQ(61)  = M_L_DQ<61>
  VSS(4)  = GND
  DQ(57)  = M_L_DQ<57>
  VSS(3)  = GND
  DQS7N  = M_L_DQS_DN<7>
  DQS7P  = M_L_DQS_DP<7>
  VSS(2)  = GND
  DQ(63)  = M_L_DQ<63>
  VSS(1)  = GND
  DQ(59)  = M_L_DQ<59>
  VSS(0)  = GND
  VDDSPD  = PVPP_KLM
  SDA  = SMB_DDR_KLM_VPP_SDA
  VPP(1)  = PVPP_KLM
  VPP(0)  = PVPP_KLM
  VPP(2)  = PVPP_KLM

(kicad_pcb
	(version 20260206)
	(generator "pcbnew")
	(generator_version "10.0")
	(general
		(thickness 1.6)
		(legacy_teardrops no)
	)
	(paper "A4")
	(title_block
		(title "Wiwynn_Tioga_Pass_MB.brd")
		(comment 1 "Tioga Pass / footprint 4281 of 4770 (J9L2), pads 101-151 of 291")
	)
	(layers
		(0 "F.Cu" signal "TOP")
		(4 "In1.Cu" signal "L2GND")
		(6 "In2.Cu" signal "L3")
		(8 "In3.Cu" signal "L4GND")
		(10 "In4.Cu" signal "L5")
		(12 "In5.Cu" signal "L6GND")
		(14 "In6.Cu" signal "L7VCC")
		(16 "In7.Cu" signal "L8VCC")
		(18 "In8.Cu" signal "L9GND")
		(20 "In9.Cu" signal "L10")
		(22 "In10.Cu" signal "L11GND")
		(24 "In11.Cu" signal "L12")
		(26 "In12.Cu" signal "L13GND")
		(2 "B.Cu" signal "BOTTOM")
		(9 "F.Adhes" user "F.Adhesive")
		(11 "B.Adhes" user "B.Adhesive")
		(13 "F.Paste" user "Package Geometry/Pastemask Top")
		(15 "B.Paste" user "Package Geometry/Pastemask Bottom")
		(5 "F.SilkS" user "Ref Des/Silkscreen Top")
		(7 "B.SilkS" user "Ref Des/Silkscreen Bottom")
		(1 "F.Mask" user "Board Geometry/Soldermask Top")
		(3 "B.Mask" user "Board Geometry/Soldermask Bottom")
		(17 "Dwgs.User" user "User.Drawings")
		(19 "Cmts.User" user "User.Comments")
		(21 "Eco1.User" user "User.Eco1")
		(23 "Eco2.User" user "User.Eco2")
		(25 "Edge.Cuts" user "Board Geometry/Outline")
		(27 "Margin" user)
		(31 "F.CrtYd" user "Package Geometry/Place Bound Top")
		(29 "B.CrtYd" user "Package Geometry/Place Bound Bottom")
		(35 "F.Fab" user "Ref Des/Assembly Top")
		(33 "B.Fab" user "Ref Des/Assembly Bottom")
	)
	(footprint ""
		(layer "B.Cu")
		(at 29.699458 -142.477236 90)
		(property "Reference" "J9L2"
			(at 2.403348 38.118542 0)
			(unlocked yes)
			(layer "B.SilkS")
			(effects
				(font
					(size 0.7874 0.5842)
					(thickness 0.1524)
				)
				(justify left mirror)
			)
		)
		(property "Value" ""
			(at 0 0 90)
			(layer "B.Fab")
			(effects
				(font
					(size 1.27 1.27)
				)
				(justify mirror)
			)
		)
		(duplicate_pad_numbers_are_jumpers no)
		(pad "98" smd rect
			(at 0 87.54999 270)
			(size 1.8034 0.508)
			(layers "B.Cu" "B.Mask" "B.Paste")
			(net "GND")
		)
		(pad "99" smd rect
			(at 0 88.399874 270)
			(size 1.8034 0.508)
			(layers "B.Cu" "B.Mask" "B.Paste")
			(net "M_L_DQS_DP<13>")
		)
		(pad "100" smd rect
			(at 0 89.250012 270)
			(size 1.8034 0.508)
			(layers "B.Cu" "B.Mask" "B.Paste")
			(net "M_L_DQS_DN<13>")
		)
		(pad "101" smd rect
			(at 0 90.099896 270)
			(size 1.8034 0.508)
			(layers "B.Cu" "B.Mask" "B.Paste")
			(net "GND")
		)
		(pad "102" smd rect
			(at 0 90.950034 270)
			(size 1.8034 0.508)
			(layers "B.Cu" "B.Mask" "B.Paste")
			(net "M_L_DQ<38>")
		)
		(pad "103" smd rect
			(at 0 91.799918 270)
			(size 1.8034 0.508)
			(layers "B.Cu" "B.Mask" "B.Paste")
			(net "GND")
		)
		(pad "104" smd rect
			(at 0 92.650056 270)
			(size 1.8034 0.508)
			(layers "B.Cu" "B.Mask" "B.Paste")
			(net "M_L_DQ<34>")
		)
		(pad "105" smd rect
			(at 0 93.49994 270)
			(size 1.8034 0.508)
			(layers "B.Cu" "B.Mask" "B.Paste")
			(net "GND")
		)
		(pad "106" smd rect
			(at 0 94.350078 270)
			(size 1.8034 0.508)
			(layers "B.Cu" "B.Mask" "B.Paste")
			(net "M_L_DQ<44>")
		)
		(pad "107" smd rect
			(at 0 95.199962 270)
			(size 1.8034 0.508)
			(layers "B.Cu" "B.Mask" "B.Paste")
			(net "GND")
		)
		(pad "108" smd rect
			(at 0 96.0501 270)
			(size 1.8034 0.508)
			(layers "B.Cu" "B.Mask" "B.Paste")
			(net "M_L_DQ<40>")
		)
		(pad "109" smd rect
			(at 0 96.899984 270)
			(size 1.8034 0.508)
			(layers "B.Cu" "B.Mask" "B.Paste")
			(net "GND")
		)
		(pad "110" smd rect
			(at 0 97.750122 270)
			(size 1.8034 0.508)
			(layers "B.Cu" "B.Mask" "B.Paste")
			(net "M_L_DQS_DP<14>")
		)
		(pad "111" smd rect
			(at 0 98.600006 270)
			(size 1.8034 0.508)
			(layers "B.Cu" "B.Mask" "B.Paste")
			(net "M_L_DQS_DN<14>")
		)
		(pad "112" smd rect
			(at 0 99.44989 270)
			(size 1.8034 0.508)
			(layers "B.Cu" "B.Mask" "B.Paste")
			(net "GND")
		)
		(pad "113" smd rect
			(at 0 100.300028 270)
			(size 1.8034 0.508)
			(layers "B.Cu" "B.Mask" "B.Paste")
			(net "M_L_DQ<46>")
		)
		(pad "114" smd rect
			(at 0 101.149912 270)
			(size 1.8034 0.508)
			(layers "B.Cu" "B.Mask" "B.Paste")
			(net "GND")
		)
		(pad "115" smd rect
			(at 0 102.00005 270)
			(size 1.8034 0.508)
			(layers "B.Cu" "B.Mask" "B.Paste")
			(net "M_L_DQ<42>")
		)
		(pad "116" smd rect
			(at 0 102.849934 270)
			(size 1.8034 0.508)
			(layers "B.Cu" "B.Mask" "B.Paste")
			(net "GND")
		)
		(pad "117" smd rect
			(at 0 103.700072 270)
			(size 1.8034 0.508)
			(layers "B.Cu" "B.Mask" "B.Paste")
			(net "M_L_DQ<52>")
		)
		(pad "118" smd rect
			(at 0 104.549956 270)
			(size 1.8034 0.508)
			(layers "B.Cu" "B.Mask" "B.Paste")
			(net "GND")
		)
		(pad "119" smd rect
			(at 0 105.400094 270)
			(size 1.8034 0.508)
			(layers "B.Cu" "B.Mask" "B.Paste")
			(net "M_L_DQ<48>")
		)
		(pad "120" smd rect
			(at 0 106.249978 270)
			(size 1.8034 0.508)
			(layers "B.Cu" "B.Mask" "B.Paste")
			(net "GND")
		)
		(pad "121" smd rect
			(at 0 107.100116 270)
			(size 1.8034 0.508)
			(layers "B.Cu" "B.Mask" "B.Paste")
			(net "M_L_DQS_DP<15>")
		)
		(pad "122" smd rect
			(at 0 107.95 270)
			(size 1.8034 0.508)
			(layers "B.Cu" "B.Mask" "B.Paste")
			(net "M_L_DQS_DN<15>")
		)
		(pad "123" smd rect
			(at 0 108.799884 270)
			(size 1.8034 0.508)
			(layers "B.Cu" "B.Mask" "B.Paste")
			(net "GND")
		)
		(pad "124" smd rect
			(at 0 109.650022 270)
			(size 1.8034 0.508)
			(layers "B.Cu" "B.Mask" "B.Paste")
			(net "M_L_DQ<54>")
		)
		(pad "125" smd rect
			(at 0 110.499906 270)
			(size 1.8034 0.508)
			(layers "B.Cu" "B.Mask" "B.Paste")
			(net "GND")
		)
		(pad "126" smd rect
			(at 0 111.350044 270)
			(size 1.8034 0.508)
			(layers "B.Cu" "B.Mask" "B.Paste")
			(net "M_L_DQ<50>")
		)
		(pad "127" smd rect
			(at 0 112.199928 270)
			(size 1.8034 0.508)
			(layers "B.Cu" "B.Mask" "B.Paste")
			(net "GND")
		)
		(pad "128" smd rect
			(at 0 113.050066 270)
			(size 1.8034 0.508)
			(layers "B.Cu" "B.Mask" "B.Paste")
			(net "M_L_DQ<60>")
		)
		(pad "129" smd rect
			(at 0 113.89995 270)
			(size 1.8034 0.508)
			(layers "B.Cu" "B.Mask" "B.Paste")
			(net "GND")
		)
		(pad "130" smd rect
			(at 0 114.750088 270)
			(size 1.8034 0.508)
			(layers "B.Cu" "B.Mask" "B.Paste")
			(net "M_L_DQ<56>")
		)
		(pad "131" smd rect
			(at 0 115.599972 270)
			(size 1.8034 0.508)
			(layers "B.Cu" "B.Mask" "B.Paste")
			(net "GND")
		)
		(pad "132" smd rect
			(at 0 116.45011 270)
			(size 1.8034 0.508)
			(layers "B.Cu" "B.Mask" "B.Paste")
			(net "M_L_DQS_DP<16>")
		)
		(pad "133" smd rect
			(at 0 117.299994 270)
			(size 1.8034 0.508)
			(layers "B.Cu" "B.Mask" "B.Paste")
			(net "M_L_DQS_DN<16>")
		)
		(pad "134" smd rect
			(at 0 118.149878 270)
			(size 1.8034 0.508)
			(layers "B.Cu" "B.Mask" "B.Paste")
			(net "GND")
		)
		(pad "135" smd rect
			(at 0 119.000016 270)
			(size 1.8034 0.508)
			(layers "B.Cu" "B.Mask" "B.Paste")
			(net "M_L_DQ<62>")
		)
		(pad "136" smd rect
			(at 0 119.8499 270)
			(size 1.8034 0.508)
			(layers "B.Cu" "B.Mask" "B.Paste")
			(net "GND")
		)
		(pad "137" smd rect
			(at 0 120.700038 270)
			(size 1.8034 0.508)
			(layers "B.Cu" "B.Mask" "B.Paste")
			(net "M_L_DQ<58>")
		)
		(pad "138" smd rect
			(at 0 121.549922 270)
			(size 1.8034 0.508)
			(layers "B.Cu" "B.Mask" "B.Paste")
			(net "GND")
		)
		(pad "139" smd rect
			(at 0 122.40006 270)
			(size 1.8034 0.508)
			(layers "B.Cu" "B.Mask" "B.Paste")
			(net "PVPP_KLM")
		)
		(pad "140" smd rect
			(at 0 123.249944 270)
			(size 1.8034 0.508)
			(layers "B.Cu" "B.Mask" "B.Paste")
			(net "PVPP_KLM")
		)
		(pad "141" smd rect
			(at 0 124.100082 270)
			(size 1.8034 0.508)
			(layers "B.Cu" "B.Mask" "B.Paste")
			(net "SMB_DDR_KLM_VPP_SCL")
		)
		(pad "142" smd rect
			(at 0 124.949966 270)
			(size 1.8034 0.508)
			(layers "B.Cu" "B.Mask" "B.Paste")
			(net "PVPP_KLM")
		)
		(pad "143" smd rect
			(at 0 125.800104 270)
			(size 1.8034 0.508)
			(layers "B.Cu" "B.Mask" "B.Paste")
			(net "PVPP_KLM")
		)
		(pad "144" smd rect
			(at 0 126.649988 270)
			(size 1.8034 0.508)
			(layers "B.Cu" "B.Mask" "B.Paste")
			(net "TP_CH_L_DIMM0_RFU_2")
		)
		(pad "145" smd rect
			(at -4.59994 0 270)
			(size 1.8034 0.508)
			(layers "B.Cu" "B.Mask" "B.Paste")
			(net "P12V_NVDIMM_KLM")
		)
		(pad "146" smd rect
			(at -4.59994 0.849884 270)
			(size 1.8034 0.508)
			(layers "B.Cu" "B.Mask" "B.Paste")
			(net "M_L_VREF")
		)
		(pad "147" smd rect
			(at -4.59994 1.700022 270)
			(size 1.8034 0.508)
			(layers "B.Cu" "B.Mask" "B.Paste")
			(net "GND")
		)
		(pad "148" smd rect
			(at -4.59994 2.549906 270)
			(size 1.8034 0.508)
			(layers "B.Cu" "B.Mask" "B.Paste")
			(net "M_L_DQ<5>")
		)
	)
)
